FILE_TYPE = MACRO_DRAWING;
SET COLOR_WIRE YELLOW;
SET COLOR_PROP ORANGE;
SET COLOR_DOT WHITE;
SET COLOR_ARC YELLOW;
SET COLOR_BODY GREEN;
SET COLOR_NOTE PURPLE;
SET PROP_DISPLAY VALUE;
SET PAGE_NUMBER P199;
FORCEADD Q_CAP..1
(-11850 7450);
FORCEPROP 1 LAST PART_NUMBER CH6101ME900
J 0
(-11800 7250);
DISPLAY 0.510638 (-11800 7250);
DISPLAY INVISIBLE (-11800 7250);
FORCEPROP 1 LAST TOLERANCE 20%
J 0
(-11800 7400);
DISPLAY 0.638298 (-11800 7400);
FORCEPROP 1 LAST MATERIAL X6S
J 0
(-11800 7350);
DISPLAY 0.638298 (-11800 7350);
FORCEPROP 1 LAST PACK_TYPE C0603
J 0
(-11800 7300);
DISPLAY 0.638298 (-11800 7300);
FORCEPROP 1 LAST VOLTAGE 6.3V
J 0
(-11800 7450);
DISPLAY 0.638298 (-11800 7450);
FORCEPROP 1 LAST VALUE 10UF
J 0
(-11800 7500);
DISPLAY 0.638298 (-11800 7500);
FORCEPROP 1 LAST $LOCATION C108
J 0
(-11800 7550);
DISPLAY 0.978723 (-11800 7550);
FORCEPROP 1 LASTPIN (-11850 7550) $PN 1
J 0
(-11840 7530);
DISPLAY 0.787234 (-11840 7530);
FORCEPROP 1 LASTPIN (-11850 7350) $PN 2
J 0
(-11840 7330);
DISPLAY 0.787234 (-11840 7330);
FORCEPROP 1 LAST PATH I19
J 0
(-11800 7600);
DISPLAY 0.978723 (-11800 7600);
PAINT WHITE (-11800 7600);
DISPLAY INVISIBLE (-11800 7600);
FORCEPROP 2 LAST CDS_LIB pure_quanta
J 0
(-11850 7450);
PAINT MONO (-11850 7450);
DISPLAY INVISIBLE (-11850 7450);
FORCEPROP 2 LAST CDS_LOCATION C108
J 0
(-11800 7650);
DISPLAY 1.021277 (-11800 7650);
DISPLAY INVISIBLE (-11800 7650);
FORCEPROP 2 LAST $SEC 1
J 0
(-11800 7650);
DISPLAY 0.680851 (-11800 7650);
PAINT MONO (-11800 7650);
DISPLAY INVISIBLE (-11800 7650);
FORCEPROP 2 LAST CDS_SEC 1
J 0
(-11800 7650);
DISPLAY 1.021277 (-11800 7650);
DISPLAY INVISIBLE (-11800 7650);
FORCEADD Q_INDUCTOR..1
(-12075 7700);
FORCEPROP 1 LAST PART_NUMBER CX601T05003
J 0
(-12200 7810);
DISPLAY 0.723404 (-12200 7810);
PAINT GREEN (-12200 7810);
DISPLAY INVISIBLE (-12200 7810);
FORCEPROP 2 LAST PACK_TYPE SMLF
J 0
(-12200 7950);
DISPLAY 0.638298 (-12200 7950);
FORCEPROP 2 LAST VALUE FCM2012KF-601T/0.5A
J 0
(-12200 7900);
DISPLAY 0.638298 (-12200 7900);
FORCEPROP 1 LAST MATERIAL IND
J 0
(-12200 7755);
DISPLAY 0.723404 (-12200 7755);
PAINT GREEN (-12200 7755);
FORCEPROP 1 LAST $LOCATION L1
J 0
(-12350 7685);
DISPLAY 0.574468 (-12350 7685);
PAINT GREEN (-12350 7685);
FORCEPROP 2 LASTPIN (-12175 7675) $PN 1
J 2
(-12185 7685);
DISPLAY 0.808511 (-12185 7685);
FORCEPROP 2 LASTPIN (-11975 7675) $PN 2
J 0
(-11965 7685);
DISPLAY 0.808511 (-11965 7685);
FORCEPROP 2 LAST CDS_LIB pure_quanta
J 0
(-12075 7700);
PAINT MONO (-12075 7700);
DISPLAY INVISIBLE (-12075 7700);
FORCEPROP 1 LAST PATH I20
J 0
(-12000 7755);
DISPLAY 0.723404 (-12000 7755);
PAINT GREEN (-12000 7755);
DISPLAY INVISIBLE (-12000 7755);
FORCEPROP 1 LAST NEEDS_NO_SIZE TRUE
J 0
(-12075 7700);
DISPLAY 0.468085 (-12075 7700);
PAINT GREEN (-12075 7700);
DISPLAY INVISIBLE (-12075 7700);
FORCEPROP 2 LAST CDS_LOCATION L1
J 0
(-12200 8000);
DISPLAY 1.021277 (-12200 8000);
DISPLAY INVISIBLE (-12200 8000);
FORCEPROP 2 LAST $SEC 1
J 0
(-12200 8000);
DISPLAY 0.680851 (-12200 8000);
PAINT MONO (-12200 8000);
DISPLAY INVISIBLE (-12200 8000);
FORCEPROP 2 LAST CDS_SEC 1
J 0
(-12200 8000);
DISPLAY 1.021277 (-12200 8000);
DISPLAY INVISIBLE (-12200 8000);
FORCEADD UNIVERSAL_POWER..1
(-12400 7975);
FORCEPROP 3 LASTPIN (-12400 7925) SIG_NAME P3V3_AUX\g
J 0
(-12390 7935);
DISPLAY 0.659574 (-12390 7935);
PAINT MONO (-12390 7935);
DISPLAY INVISIBLE (-12390 7935);
FORCEPROP 1 LAST HDL_POWER P3V3_AUX
J 1
(-12400 8025);
DISPLAY 0.872340 (-12400 8025);
PAINT GREEN (-12400 8025);
FORCEPROP 2 LAST CDS_LIB logical_power
J 0
(-12400 7975);
PAINT MONO (-12400 7975);
DISPLAY INVISIBLE (-12400 7975);
FORCEPROP 1 LAST PATH I21
J 0
(-12350 8000);
DISPLAY 0.872340 (-12350 8000);
PAINT AQUA (-12350 8000);
DISPLAY INVISIBLE (-12350 8000);
FORCEADD UNIVERSAL_POWER..1
(-8850 7825);
FORCEPROP 3 LASTPIN (-8850 7775) SIG_NAME P3V3_AUX_CLK_GEN_VDDA100M_CK440\g
J 0
(-8840 7785);
DISPLAY 0.659574 (-8840 7785);
PAINT MONO (-8840 7785);
DISPLAY INVISIBLE (-8840 7785);
FORCEPROP 1 LAST HDL_POWER P3V3_AUX_CLK_GEN_VDDA100M_CK440
J 1
(-8850 7875);
DISPLAY 0.872340 (-8850 7875);
PAINT GREEN (-8850 7875);
FORCEPROP 2 LAST CDS_LIB logical_power
J 0
(-8850 7825);
PAINT MONO (-8850 7825);
DISPLAY INVISIBLE (-8850 7825);
FORCEPROP 1 LAST PATH I3
J 0
(-8800 7850);
DISPLAY 0.872340 (-8800 7850);
PAINT AQUA (-8800 7850);
DISPLAY INVISIBLE (-8800 7850);
FORCEADD UNIVERSAL_POWER..1
(-8850 6600);
FORCEPROP 3 LASTPIN (-8850 6550) SIG_NAME P3V3_AUX_CLK_GEN_VDDA25M_CK440\g
J 0
(-8840 6560);
DISPLAY 0.659574 (-8840 6560);
PAINT MONO (-8840 6560);
DISPLAY INVISIBLE (-8840 6560);
FORCEPROP 1 LAST HDL_POWER P3V3_AUX_CLK_GEN_VDDA25M_CK440
J 1
(-8850 6650);
DISPLAY 0.872340 (-8850 6650);
PAINT GREEN (-8850 6650);
FORCEPROP 2 LAST CDS_LIB logical_power
J 0
(-8850 6600);
PAINT MONO (-8850 6600);
DISPLAY INVISIBLE (-8850 6600);
FORCEPROP 1 LAST PATH I31
J 0
(-8800 6625);
DISPLAY 0.872340 (-8800 6625);
PAINT AQUA (-8800 6625);
DISPLAY INVISIBLE (-8800 6625);
FORCEADD UNIVERSAL_POWER..1
(-10200 6600);
FORCEPROP 3 LASTPIN (-10200 6550) SIG_NAME P3V3_AUX_CLK_GEN_VDDXTAL_CK440\g
J 0
(-10190 6560);
DISPLAY 0.659574 (-10190 6560);
PAINT MONO (-10190 6560);
DISPLAY INVISIBLE (-10190 6560);
FORCEPROP 1 LAST HDL_POWER P3V3_AUX_CLK_GEN_VDDXTAL_CK440
J 1
(-10200 6650);
DISPLAY 0.872340 (-10200 6650);
PAINT GREEN (-10200 6650);
FORCEPROP 2 LAST CDS_LIB logical_power
J 0
(-10200 6600);
PAINT MONO (-10200 6600);
DISPLAY INVISIBLE (-10200 6600);
FORCEPROP 1 LAST PATH I35
J 0
(-10150 6625);
DISPLAY 0.872340 (-10150 6625);
PAINT AQUA (-10150 6625);
DISPLAY INVISIBLE (-10150 6625);
FORCEADD Q_RES..1
(-9775 6450);
FORCEPROP 1 LAST PART_NUMBER CS-1003F900
J 0
(-9925 6525);
DISPLAY 0.510638 (-9925 6525);
DISPLAY INVISIBLE (-9925 6525);
FORCEPROP 1 LAST PACK_TYPE 0603LF
J 0
(-9925 6575);
DISPLAY 0.510638 (-9925 6575);
FORCEPROP 1 LAST TOLERANCE 1%
J 0
(-9550 6450);
DISPLAY 0.638298 (-9550 6450);
FORCEPROP 1 LAST WATTAGE 1/10W
J 2
(-9600 6575);
DISPLAY 0.510638 (-9600 6575);
FORCEPROP 1 LAST VALUE 1
J 2
(-9575 6450);
DISPLAY 0.638298 (-9575 6450);
FORCEPROP 1 LAST MATERIAL CHIP
J 0
(-9450 6450);
DISPLAY 0.638298 (-9450 6450);
FORCEPROP 1 LAST $LOCATION R442
J 0
(-10050 6450);
DISPLAY 0.978723 (-10050 6450);
FORCEPROP 2 LAST CDS_LIB pure_quanta
J 0
(-9775 6450);
PAINT MONO (-9775 6450);
DISPLAY INVISIBLE (-9775 6450);
FORCEPROP 1 LAST PATH I36
J 0
(-9825 6600);
DISPLAY 0.978723 (-9825 6600);
PAINT WHITE (-9825 6600);
DISPLAY INVISIBLE (-9825 6600);
FORCEPROP 2 LAST CDS_LOCATION R442
J 0
(-9825 6650);
DISPLAY 1.021277 (-9825 6650);
DISPLAY INVISIBLE (-9825 6650);
FORCEPROP 2 LAST $SEC 1
J 0
(-9825 6650);
DISPLAY 0.680851 (-9825 6650);
PAINT MONO (-9825 6650);
DISPLAY INVISIBLE (-9825 6650);
FORCEPROP 2 LAST CDS_SEC 1
J 0
(-9825 6650);
DISPLAY 1.021277 (-9825 6650);
DISPLAY INVISIBLE (-9825 6650);
FORCEPROP 1 LASTPIN (-9875 6450) $PN 1
J 0
(-9863 6462);
DISPLAY 0.787234 (-9863 6462);
DISPLAY INVISIBLE (-9863 6462);
FORCEPROP 1 LASTPIN (-9675 6450) $PN 2
J 0
(-9713 6462);
DISPLAY 0.787234 (-9713 6462);
DISPLAY INVISIBLE (-9713 6462);
FORCEADD Q_INDUCTOR..1
(-12075 6475);
FORCEPROP 1 LAST PART_NUMBER CX601T05003
J 0
(-12200 6585);
DISPLAY 0.723404 (-12200 6585);
PAINT GREEN (-12200 6585);
DISPLAY INVISIBLE (-12200 6585);
FORCEPROP 2 LAST VALUE FCM2012KF-601T/0.5A
J 0
(-12200 6675);
DISPLAY 0.638298 (-12200 6675);
FORCEPROP 1 LAST MATERIAL IND
J 0
(-12200 6530);
DISPLAY 0.723404 (-12200 6530);
PAINT GREEN (-12200 6530);
FORCEPROP 2 LAST PACK_TYPE SMLF
J 0
(-12200 6725);
DISPLAY 0.638298 (-12200 6725);
FORCEPROP 1 LAST $LOCATION L13
J 0
(-12325 6460);
DISPLAY 0.574468 (-12325 6460);
PAINT GREEN (-12325 6460);
FORCEPROP 2 LASTPIN (-12175 6450) $PN 1
J 2
(-12185 6460);
DISPLAY 0.808511 (-12185 6460);
FORCEPROP 2 LASTPIN (-11975 6450) $PN 2
J 0
(-11965 6460);
DISPLAY 0.808511 (-11965 6460);
FORCEPROP 1 LAST NEEDS_NO_SIZE TRUE
J 0
(-12075 6475);
DISPLAY 0.468085 (-12075 6475);
PAINT GREEN (-12075 6475);
DISPLAY INVISIBLE (-12075 6475);
FORCEPROP 1 LAST PATH I41
J 0
(-12000 6530);
DISPLAY 0.723404 (-12000 6530);
PAINT GREEN (-12000 6530);
DISPLAY INVISIBLE (-12000 6530);
FORCEPROP 2 LAST CDS_LIB pure_quanta
J 0
(-12075 6475);
PAINT MONO (-12075 6475);
DISPLAY INVISIBLE (-12075 6475);
FORCEPROP 2 LAST CDS_LOCATION L13
J 0
(-12200 6775);
DISPLAY 1.021277 (-12200 6775);
DISPLAY INVISIBLE (-12200 6775);
FORCEPROP 2 LAST $SEC 1
J 0
(-12200 6775);
DISPLAY 0.680851 (-12200 6775);
PAINT MONO (-12200 6775);
DISPLAY INVISIBLE (-12200 6775);
FORCEPROP 2 LAST CDS_SEC 1
J 0
(-12200 6775);
DISPLAY 1.021277 (-12200 6775);
DISPLAY INVISIBLE (-12200 6775);
FORCEADD UNIVERSAL_POWER..1
(-12400 6750);
FORCEPROP 3 LASTPIN (-12400 6700) SIG_NAME P3V3_AUX\g
J 0
(-12390 6710);
DISPLAY 0.659574 (-12390 6710);
PAINT MONO (-12390 6710);
DISPLAY INVISIBLE (-12390 6710);
FORCEPROP 1 LAST HDL_POWER P3V3_AUX
J 1
(-12400 6800);
DISPLAY 0.872340 (-12400 6800);
PAINT GREEN (-12400 6800);
FORCEPROP 2 LAST CDS_LIB logical_power
J 0
(-12400 6750);
PAINT MONO (-12400 6750);
DISPLAY INVISIBLE (-12400 6750);
FORCEPROP 1 LAST PATH I42
J 0
(-12350 6775);
DISPLAY 0.872340 (-12350 6775);
PAINT AQUA (-12350 6775);
DISPLAY INVISIBLE (-12350 6775);
FORCEADD Q_CAP..1
(-11500 6225);
FORCEPROP 1 LAST PART_NUMBER CH5104KEB02
J 0
(-11450 6025);
DISPLAY 0.510638 (-11450 6025);
DISPLAY INVISIBLE (-11450 6025);
FORCEPROP 1 LAST PACK_TYPE C0402
J 0
(-11450 6075);
DISPLAY 0.638298 (-11450 6075);
FORCEPROP 1 LAST MATERIAL X6S
J 0
(-11450 6125);
DISPLAY 0.638298 (-11450 6125);
FORCEPROP 1 LAST VOLTAGE 25V
J 0
(-11450 6225);
DISPLAY 0.638298 (-11450 6225);
FORCEPROP 1 LAST TOLERANCE 10%
J 0
(-11450 6175);
DISPLAY 0.638298 (-11450 6175);
FORCEPROP 1 LAST VALUE 1UF
J 0
(-11450 6275);
DISPLAY 0.638298 (-11450 6275);
FORCEPROP 1 LAST $LOCATION C1311
J 0
(-11450 6325);
DISPLAY 0.978723 (-11450 6325);
FORCEPROP 1 LASTPIN (-11500 6325) $PN 1
J 0
(-11490 6305);
DISPLAY 0.787234 (-11490 6305);
FORCEPROP 1 LASTPIN (-11500 6125) $PN 2
J 0
(-11490 6105);
DISPLAY 0.787234 (-11490 6105);
FORCEPROP 2 LAST CDS_LIB pure_quanta
J 0
(-11500 6225);
PAINT MONO (-11500 6225);
DISPLAY INVISIBLE (-11500 6225);
FORCEPROP 1 LAST PATH I43
J 0
(-11450 6375);
DISPLAY 0.978723 (-11450 6375);
PAINT WHITE (-11450 6375);
DISPLAY INVISIBLE (-11450 6375);
FORCEPROP 2 LAST BOM_COST VR_SYSTEM 
J 0
(-11450 6375);
DISPLAY 0.680851 (-11450 6375);
DISPLAY INVISIBLE (-11450 6375);
FORCEPROP 2 LAST CDS_LOCATION C1311
J 0
(-11450 6425);
DISPLAY 1.021277 (-11450 6425);
DISPLAY INVISIBLE (-11450 6425);
FORCEPROP 2 LAST $SEC 1
J 0
(-11450 6425);
DISPLAY 0.680851 (-11450 6425);
PAINT MONO (-11450 6425);
DISPLAY INVISIBLE (-11450 6425);
FORCEPROP 2 LAST CDS_SEC 1
J 0
(-11450 6425);
DISPLAY 1.021277 (-11450 6425);
DISPLAY INVISIBLE (-11450 6425);
FORCEADD Q_CAP..1
(-11850 6225);
FORCEPROP 1 LAST PART_NUMBER CH6101ME900
J 0
(-11800 6025);
DISPLAY 0.510638 (-11800 6025);
DISPLAY INVISIBLE (-11800 6025);
FORCEPROP 1 LAST VALUE 10UF
J 0
(-11800 6275);
DISPLAY 0.638298 (-11800 6275);
FORCEPROP 1 LAST TOLERANCE 20%
J 0
(-11800 6175);
DISPLAY 0.638298 (-11800 6175);
FORCEPROP 1 LAST PACK_TYPE C0603
J 0
(-11800 6075);
DISPLAY 0.638298 (-11800 6075);
FORCEPROP 1 LAST VOLTAGE 6.3V
J 0
(-11800 6225);
DISPLAY 0.638298 (-11800 6225);
FORCEPROP 1 LAST MATERIAL X6S
J 0
(-11800 6125);
DISPLAY 0.638298 (-11800 6125);
FORCEPROP 1 LAST $LOCATION C1309
J 0
(-11800 6325);
DISPLAY 0.978723 (-11800 6325);
FORCEPROP 1 LASTPIN (-11850 6325) $PN 1
J 0
(-11840 6305);
DISPLAY 0.787234 (-11840 6305);
FORCEPROP 1 LASTPIN (-11850 6125) $PN 2
J 0
(-11840 6105);
DISPLAY 0.787234 (-11840 6105);
FORCEPROP 1 LAST PATH I44
J 0
(-11800 6375);
DISPLAY 0.978723 (-11800 6375);
PAINT WHITE (-11800 6375);
DISPLAY INVISIBLE (-11800 6375);
FORCEPROP 2 LAST CDS_LIB pure_quanta
J 0
(-11850 6225);
PAINT MONO (-11850 6225);
DISPLAY INVISIBLE (-11850 6225);
FORCEPROP 2 LAST CDS_LOCATION C1309
J 0
(-11800 6425);
DISPLAY 1.021277 (-11800 6425);
DISPLAY INVISIBLE (-11800 6425);
FORCEPROP 2 LAST $SEC 1
J 0
(-11800 6425);
DISPLAY 0.680851 (-11800 6425);
PAINT MONO (-11800 6425);
DISPLAY INVISIBLE (-11800 6425);
FORCEPROP 2 LAST CDS_SEC 1
J 0
(-11800 6425);
DISPLAY 1.021277 (-11800 6425);
DISPLAY INVISIBLE (-11800 6425);
FORCEADD Q_CAP..1
(-9250 6225);
FORCEPROP 1 LAST PART_NUMBER CH6101ME900
J 0
(-9200 6075);
DISPLAY 0.638298 (-9200 6075);
DISPLAY INVISIBLE (-9200 6075);
FORCEPROP 1 LAST PACK_TYPE C0603
J 0
(-9200 6025);
DISPLAY 0.638298 (-9200 6025);
FORCEPROP 1 LAST VALUE 10UF
J 0
(-9200 6275);
DISPLAY 0.638298 (-9200 6275);
FORCEPROP 1 LAST VOLTAGE 6.3V
J 0
(-9200 6225);
DISPLAY 0.638298 (-9200 6225);
FORCEPROP 1 LAST TOLERANCE 20%
J 0
(-9200 6175);
DISPLAY 0.638298 (-9200 6175);
FORCEPROP 1 LAST MATERIAL X6S
J 0
(-9200 6125);
DISPLAY 0.638298 (-9200 6125);
FORCEPROP 1 LAST $LOCATION C1313
J 0
(-9200 6325);
DISPLAY 0.978723 (-9200 6325);
FORCEPROP 1 LASTPIN (-9250 6325) $PN 1
J 0
(-9240 6305);
DISPLAY 0.787234 (-9240 6305);
FORCEPROP 1 LASTPIN (-9250 6125) $PN 2
J 0
(-9240 6105);
DISPLAY 0.787234 (-9240 6105);
FORCEPROP 1 LAST PATH I48
J 0
(-9200 6375);
DISPLAY 0.978723 (-9200 6375);
PAINT WHITE (-9200 6375);
DISPLAY INVISIBLE (-9200 6375);
FORCEPROP 2 LAST CDS_LIB pure_quanta
J 0
(-9250 6225);
PAINT MONO (-9250 6225);
DISPLAY INVISIBLE (-9250 6225);
FORCEPROP 2 LAST CDS_LOCATION C1313
J 0
(-9200 6425);
DISPLAY 1.021277 (-9200 6425);
DISPLAY INVISIBLE (-9200 6425);
FORCEPROP 2 LAST $SEC 1
J 0
(-9200 6425);
DISPLAY 0.680851 (-9200 6425);
PAINT MONO (-9200 6425);
DISPLAY INVISIBLE (-9200 6425);
FORCEPROP 2 LAST CDS_SEC 1
J 0
(-9200 6425);
DISPLAY 1.021277 (-9200 6425);
DISPLAY INVISIBLE (-9200 6425);
FORCEADD UNIVERSAL_POWER..1
(-8850 5300);
FORCEPROP 3 LASTPIN (-8850 5250) SIG_NAME P3V3_AUX_CLK_GEN_VDDPT_CK440\g
J 0
(-8840 5260);
DISPLAY 0.659574 (-8840 5260);
PAINT MONO (-8840 5260);
DISPLAY INVISIBLE (-8840 5260);
FORCEPROP 1 LAST HDL_POWER P3V3_AUX_CLK_GEN_VDDPT_CK440
J 1
(-8850 5350);
DISPLAY 0.872340 (-8850 5350);
PAINT GREEN (-8850 5350);
FORCEPROP 2 LAST CDS_LIB logical_power
J 0
(-8850 5300);
PAINT MONO (-8850 5300);
DISPLAY INVISIBLE (-8850 5300);
FORCEPROP 1 LAST PATH I51
J 0
(-8800 5325);
DISPLAY 0.872340 (-8800 5325);
PAINT AQUA (-8800 5325);
DISPLAY INVISIBLE (-8800 5325);
FORCEADD Q_CAP..1
(-9250 4925);
FORCEPROP 1 LAST PART_NUMBER CH6101ME900
J 0
(-9200 4775);
DISPLAY 0.638298 (-9200 4775);
DISPLAY INVISIBLE (-9200 4775);
FORCEPROP 1 LAST PACK_TYPE C0603
J 0
(-9200 4725);
DISPLAY 0.638298 (-9200 4725);
FORCEPROP 1 LAST VALUE 10UF
J 0
(-9200 4975);
DISPLAY 0.638298 (-9200 4975);
FORCEPROP 1 LAST TOLERANCE 20%
J 0
(-9200 4875);
DISPLAY 0.638298 (-9200 4875);
FORCEPROP 1 LAST VOLTAGE 6.3V
J 0
(-9200 4925);
DISPLAY 0.638298 (-9200 4925);
FORCEPROP 1 LAST MATERIAL X6S
J 0
(-9200 4825);
DISPLAY 0.638298 (-9200 4825);
FORCEPROP 1 LAST $LOCATION C1314
J 0
(-9200 5025);
DISPLAY 0.978723 (-9200 5025);
FORCEPROP 1 LASTPIN (-9250 5025) $PN 1
J 0
(-9240 5005);
DISPLAY 0.787234 (-9240 5005);
FORCEPROP 1 LASTPIN (-9250 4825) $PN 2
J 0
(-9240 4805);
DISPLAY 0.787234 (-9240 4805);
FORCEPROP 2 LAST CDS_LIB pure_quanta
J 0
(-9250 4925);
PAINT MONO (-9250 4925);
DISPLAY INVISIBLE (-9250 4925);
FORCEPROP 1 LAST PATH I53
J 0
(-9200 5075);
DISPLAY 0.978723 (-9200 5075);
PAINT WHITE (-9200 5075);
DISPLAY INVISIBLE (-9200 5075);
FORCEPROP 2 LAST CDS_LOCATION C1314
J 0
(-9200 5125);
DISPLAY 1.021277 (-9200 5125);
DISPLAY INVISIBLE (-9200 5125);
FORCEPROP 2 LAST $SEC 1
J 0
(-9200 5125);
DISPLAY 0.680851 (-9200 5125);
PAINT MONO (-9200 5125);
DISPLAY INVISIBLE (-9200 5125);
FORCEPROP 2 LAST CDS_SEC 1
J 0
(-9200 5125);
DISPLAY 1.021277 (-9200 5125);
DISPLAY INVISIBLE (-9200 5125);
FORCEADD Q_RES..1
(-9775 5150);
FORCEPROP 1 LAST PART_NUMBER CS-1003F900
J 0
(-9925 5225);
DISPLAY 0.510638 (-9925 5225);
DISPLAY INVISIBLE (-9925 5225);
FORCEPROP 1 LAST PACK_TYPE 0603LF
J 0
(-9925 5275);
DISPLAY 0.510638 (-9925 5275);
FORCEPROP 1 LAST WATTAGE 1/10W
J 2
(-9600 5275);
DISPLAY 0.510638 (-9600 5275);
FORCEPROP 1 LAST TOLERANCE 1%
J 0
(-9550 5150);
DISPLAY 0.638298 (-9550 5150);
FORCEPROP 1 LAST MATERIAL CHIP
J 0
(-9450 5150);
DISPLAY 0.638298 (-9450 5150);
FORCEPROP 1 LAST VALUE 1
J 2
(-9575 5150);
DISPLAY 0.638298 (-9575 5150);
FORCEPROP 1 LAST $LOCATION R447
J 0
(-10050 5150);
DISPLAY 0.978723 (-10050 5150);
FORCEPROP 1 LASTPIN (-9875 5150) $PN 1
J 0
(-9863 5162);
DISPLAY 0.787234 (-9863 5162);
FORCEPROP 1 LASTPIN (-9675 5150) $PN 2
J 0
(-9713 5162);
DISPLAY 0.787234 (-9713 5162);
FORCEPROP 2 LAST CDS_LIB pure_quanta
J 0
(-9775 5150);
PAINT MONO (-9775 5150);
DISPLAY INVISIBLE (-9775 5150);
FORCEPROP 1 LAST PATH I55
J 0
(-9825 5300);
DISPLAY 0.978723 (-9825 5300);
PAINT WHITE (-9825 5300);
DISPLAY INVISIBLE (-9825 5300);
FORCEPROP 2 LAST CDS_LOCATION R447
J 0
(-9825 5350);
DISPLAY 1.021277 (-9825 5350);
DISPLAY INVISIBLE (-9825 5350);
FORCEPROP 2 LAST $SEC 1
J 0
(-9825 5350);
DISPLAY 0.680851 (-9825 5350);
PAINT MONO (-9825 5350);
DISPLAY INVISIBLE (-9825 5350);
FORCEPROP 2 LAST CDS_SEC 1
J 0
(-9825 5350);
DISPLAY 1.021277 (-9825 5350);
DISPLAY INVISIBLE (-9825 5350);
FORCEADD UNIVERSAL_POWER..1
(-10200 5300);
FORCEPROP 3 LASTPIN (-10200 5250) SIG_NAME P3V3_AUX_CLK_GEN_VDDMXCK_CK440\g
J 0
(-10190 5260);
DISPLAY 0.659574 (-10190 5260);
PAINT MONO (-10190 5260);
DISPLAY INVISIBLE (-10190 5260);
FORCEPROP 1 LAST HDL_POWER P3V3_AUX_CLK_GEN_VDDMXCK_CK440
J 1
(-10200 5350);
DISPLAY 0.872340 (-10200 5350);
PAINT GREEN (-10200 5350);
FORCEPROP 2 LAST CDS_LIB logical_power
J 0
(-10200 5300);
PAINT MONO (-10200 5300);
DISPLAY INVISIBLE (-10200 5300);
FORCEPROP 1 LAST PATH I56
J 0
(-10150 5325);
DISPLAY 0.872340 (-10150 5325);
PAINT AQUA (-10150 5325);
DISPLAY INVISIBLE (-10150 5325);
FORCEADD Q_CAP..1
(-11500 4925);
FORCEPROP 1 LAST PART_NUMBER CH5104KEB02
J 0
(-11450 4725);
DISPLAY 0.510638 (-11450 4725);
DISPLAY INVISIBLE (-11450 4725);
FORCEPROP 1 LAST PACK_TYPE C0402
J 0
(-11450 4775);
DISPLAY 0.638298 (-11450 4775);
FORCEPROP 1 LAST VALUE 1UF
J 0
(-11450 4975);
DISPLAY 0.638298 (-11450 4975);
FORCEPROP 1 LAST VOLTAGE 25V
J 0
(-11450 4925);
DISPLAY 0.638298 (-11450 4925);
FORCEPROP 1 LAST MATERIAL X6S
J 0
(-11450 4825);
DISPLAY 0.638298 (-11450 4825);
FORCEPROP 1 LAST TOLERANCE 10%
J 0
(-11450 4875);
DISPLAY 0.638298 (-11450 4875);
FORCEPROP 1 LAST $LOCATION C1312
J 0
(-11450 5025);
DISPLAY 0.978723 (-11450 5025);
FORCEPROP 1 LASTPIN (-11500 5025) $PN 1
J 0
(-11490 5005);
DISPLAY 0.787234 (-11490 5005);
FORCEPROP 1 LASTPIN (-11500 4825) $PN 2
J 0
(-11490 4805);
DISPLAY 0.787234 (-11490 4805);
FORCEPROP 2 LAST CDS_LIB pure_quanta
J 0
(-11500 4925);
PAINT MONO (-11500 4925);
DISPLAY INVISIBLE (-11500 4925);
FORCEPROP 1 LAST PATH I58
J 0
(-11450 5075);
DISPLAY 0.978723 (-11450 5075);
PAINT WHITE (-11450 5075);
DISPLAY INVISIBLE (-11450 5075);
FORCEPROP 2 LAST BOM_COST VR_SYSTEM 
J 0
(-11450 5075);
DISPLAY 0.680851 (-11450 5075);
DISPLAY INVISIBLE (-11450 5075);
FORCEPROP 2 LAST CDS_LOCATION C1312
J 0
(-11450 5125);
DISPLAY 1.021277 (-11450 5125);
DISPLAY INVISIBLE (-11450 5125);
FORCEPROP 2 LAST $SEC 1
J 0
(-11450 5125);
DISPLAY 0.680851 (-11450 5125);
PAINT MONO (-11450 5125);
DISPLAY INVISIBLE (-11450 5125);
FORCEPROP 2 LAST CDS_SEC 1
J 0
(-11450 5125);
DISPLAY 1.021277 (-11450 5125);
DISPLAY INVISIBLE (-11450 5125);
FORCEADD Q_CAP..1
(-11850 4925);
FORCEPROP 1 LAST PART_NUMBER CH6101ME900
J 0
(-11800 4725);
DISPLAY 0.510638 (-11800 4725);
DISPLAY INVISIBLE (-11800 4725);
FORCEPROP 1 LAST PACK_TYPE C0603
J 0
(-11800 4775);
DISPLAY 0.638298 (-11800 4775);
FORCEPROP 1 LAST VALUE 10UF
J 0
(-11800 4975);
DISPLAY 0.638298 (-11800 4975);
FORCEPROP 1 LAST VOLTAGE 6.3V
J 0
(-11800 4925);
DISPLAY 0.638298 (-11800 4925);
FORCEPROP 1 LAST TOLERANCE 20%
J 0
(-11800 4875);
DISPLAY 0.638298 (-11800 4875);
FORCEPROP 1 LAST MATERIAL X6S
J 0
(-11800 4825);
DISPLAY 0.638298 (-11800 4825);
FORCEPROP 1 LAST $LOCATION C1310
J 0
(-11800 5025);
DISPLAY 0.978723 (-11800 5025);
FORCEPROP 1 LASTPIN (-11850 5025) $PN 1
J 0
(-11840 5005);
DISPLAY 0.787234 (-11840 5005);
FORCEPROP 1 LASTPIN (-11850 4825) $PN 2
J 0
(-11840 4805);
DISPLAY 0.787234 (-11840 4805);
FORCEPROP 2 LAST CDS_LIB pure_quanta
J 0
(-11850 4925);
PAINT MONO (-11850 4925);
DISPLAY INVISIBLE (-11850 4925);
FORCEPROP 1 LAST PATH I59
J 0
(-11800 5075);
DISPLAY 0.978723 (-11800 5075);
PAINT WHITE (-11800 5075);
DISPLAY INVISIBLE (-11800 5075);
FORCEPROP 2 LAST CDS_LOCATION C1310
J 0
(-11800 5125);
DISPLAY 1.021277 (-11800 5125);
DISPLAY INVISIBLE (-11800 5125);
FORCEPROP 2 LAST $SEC 1
J 0
(-11800 5125);
DISPLAY 0.680851 (-11800 5125);
PAINT MONO (-11800 5125);
DISPLAY INVISIBLE (-11800 5125);
FORCEPROP 2 LAST CDS_SEC 1
J 0
(-11800 5125);
DISPLAY 1.021277 (-11800 5125);
DISPLAY INVISIBLE (-11800 5125);
FORCEADD Q_CAP..1
(-9250 7450);
FORCEPROP 1 LAST PART_NUMBER CH6101ME900
J 0
(-9200 7300);
DISPLAY 0.638298 (-9200 7300);
DISPLAY INVISIBLE (-9200 7300);
FORCEPROP 1 LAST PACK_TYPE C0603
J 0
(-9200 7250);
DISPLAY 0.638298 (-9200 7250);
FORCEPROP 1 LAST VALUE 10UF
J 0
(-9200 7500);
DISPLAY 0.638298 (-9200 7500);
FORCEPROP 1 LAST MATERIAL X6S
J 0
(-9200 7350);
DISPLAY 0.638298 (-9200 7350);
FORCEPROP 1 LAST TOLERANCE 20%
J 0
(-9200 7400);
DISPLAY 0.638298 (-9200 7400);
FORCEPROP 1 LAST VOLTAGE 6.3V
J 0
(-9200 7450);
DISPLAY 0.638298 (-9200 7450);
FORCEPROP 1 LAST $LOCATION C172
J 0
(-9200 7550);
DISPLAY 0.978723 (-9200 7550);
FORCEPROP 1 LASTPIN (-9250 7550) $PN 1
J 0
(-9240 7530);
DISPLAY 0.787234 (-9240 7530);
FORCEPROP 1 LASTPIN (-9250 7350) $PN 2
J 0
(-9240 7330);
DISPLAY 0.787234 (-9240 7330);
FORCEPROP 2 LAST CDS_LIB pure_quanta
J 0
(-9250 7450);
PAINT MONO (-9250 7450);
DISPLAY INVISIBLE (-9250 7450);
FORCEPROP 1 LAST PATH I6
J 0
(-9200 7600);
DISPLAY 0.978723 (-9200 7600);
PAINT WHITE (-9200 7600);
DISPLAY INVISIBLE (-9200 7600);
FORCEPROP 2 LAST CDS_LOCATION C172
J 0
(-9200 7650);
DISPLAY 1.021277 (-9200 7650);
DISPLAY INVISIBLE (-9200 7650);
FORCEPROP 2 LAST $SEC 1
J 0
(-9200 7650);
DISPLAY 0.680851 (-9200 7650);
PAINT MONO (-9200 7650);
DISPLAY INVISIBLE (-9200 7650);
FORCEPROP 2 LAST CDS_SEC 1
J 0
(-9200 7650);
DISPLAY 1.021277 (-9200 7650);
DISPLAY INVISIBLE (-9200 7650);
FORCEADD Q_INDUCTOR..1
(-12075 5175);
FORCEPROP 1 LAST PART_NUMBER CX601T05003
J 0
(-12200 5285);
DISPLAY 0.723404 (-12200 5285);
PAINT GREEN (-12200 5285);
DISPLAY INVISIBLE (-12200 5285);
FORCEPROP 2 LAST VALUE FCM2012KF-601T/0.5A
J 0
(-12200 5375);
DISPLAY 0.638298 (-12200 5375);
FORCEPROP 1 LAST MATERIAL IND
J 0
(-12200 5230);
DISPLAY 0.723404 (-12200 5230);
PAINT GREEN (-12200 5230);
FORCEPROP 2 LAST PACK_TYPE SMLF
J 0
(-12200 5425);
DISPLAY 0.638298 (-12200 5425);
FORCEPROP 1 LAST $LOCATION L14
J 0
(-12325 5160);
DISPLAY 0.574468 (-12325 5160);
PAINT GREEN (-12325 5160);
FORCEPROP 2 LASTPIN (-12175 5150) $PN 1
J 2
(-12185 5160);
DISPLAY 0.808511 (-12185 5160);
FORCEPROP 2 LASTPIN (-11975 5150) $PN 2
J 0
(-11965 5160);
DISPLAY 0.808511 (-11965 5160);
FORCEPROP 2 LAST CDS_LIB pure_quanta
J 0
(-12075 5175);
PAINT MONO (-12075 5175);
DISPLAY INVISIBLE (-12075 5175);
FORCEPROP 1 LAST PATH I60
J 0
(-12000 5230);
DISPLAY 0.723404 (-12000 5230);
PAINT GREEN (-12000 5230);
DISPLAY INVISIBLE (-12000 5230);
FORCEPROP 1 LAST NEEDS_NO_SIZE TRUE
J 0
(-12075 5175);
DISPLAY 0.468085 (-12075 5175);
PAINT GREEN (-12075 5175);
DISPLAY INVISIBLE (-12075 5175);
FORCEPROP 2 LAST CDS_LOCATION L14
J 0
(-12200 5475);
DISPLAY 1.021277 (-12200 5475);
DISPLAY INVISIBLE (-12200 5475);
FORCEPROP 2 LAST $SEC 1
J 0
(-12200 5475);
DISPLAY 0.680851 (-12200 5475);
PAINT MONO (-12200 5475);
DISPLAY INVISIBLE (-12200 5475);
FORCEPROP 2 LAST CDS_SEC 1
J 0
(-12200 5475);
DISPLAY 1.021277 (-12200 5475);
DISPLAY INVISIBLE (-12200 5475);
FORCEADD UNIVERSAL_POWER..1
(-12400 5450);
FORCEPROP 3 LASTPIN (-12400 5400) SIG_NAME P3V3_AUX\g
J 0
(-12390 5410);
DISPLAY 0.659574 (-12390 5410);
PAINT MONO (-12390 5410);
DISPLAY INVISIBLE (-12390 5410);
FORCEPROP 1 LAST HDL_POWER P3V3_AUX
J 1
(-12400 5500);
DISPLAY 0.872340 (-12400 5500);
PAINT GREEN (-12400 5500);
FORCEPROP 2 LAST CDS_LIB logical_power
J 0
(-12400 5450);
PAINT MONO (-12400 5450);
DISPLAY INVISIBLE (-12400 5450);
FORCEPROP 1 LAST PATH I61
J 0
(-12350 5475);
DISPLAY 0.872340 (-12350 5475);
PAINT AQUA (-12350 5475);
DISPLAY INVISIBLE (-12350 5475);
FORCEADD UNIVERSAL_GND..1
(-10900 7075);
FORCEPROP 3 LASTPIN (-10900 7125) SIG_NAME GND\g
J 0
(-10890 7135);
DISPLAY 0.659574 (-10890 7135);
PAINT MONO (-10890 7135);
DISPLAY INVISIBLE (-10890 7135);
FORCEPROP 2 LAST CDS_LIB logical_power
J 0
(-10900 7075);
DISPLAY INVISIBLE (-10900 7075);
FORCEPROP 1 LAST PATH I69
J 0
(-10825 7075);
DISPLAY 0.872340 (-10825 7075);
PAINT AQUA (-10825 7075);
DISPLAY INVISIBLE (-10825 7075);
FORCEPROP 1 LAST HDL_POWER GND
J 1
(-10875 7000);
DISPLAY 0.872340 (-10875 7000);
PAINT GREEN (-10875 7000);
DISPLAY INVISIBLE (-10875 7000);
FORCEADD Q_RES..1
(-9775 7675);
FORCEPROP 1 LAST PART_NUMBER CS-1003F900
J 0
(-9925 7750);
DISPLAY 0.510638 (-9925 7750);
DISPLAY INVISIBLE (-9925 7750);
FORCEPROP 1 LAST PACK_TYPE 0603LF
J 0
(-9925 7800);
DISPLAY 0.510638 (-9925 7800);
FORCEPROP 1 LAST WATTAGE 1/10W
J 2
(-9600 7800);
DISPLAY 0.510638 (-9600 7800);
FORCEPROP 1 LAST TOLERANCE 1%
J 0
(-9550 7675);
DISPLAY 0.638298 (-9550 7675);
FORCEPROP 1 LAST MATERIAL CHIP
J 0
(-9450 7675);
DISPLAY 0.638298 (-9450 7675);
FORCEPROP 1 LAST VALUE 1
J 2
(-9575 7675);
DISPLAY 0.638298 (-9575 7675);
FORCEPROP 1 LAST $LOCATION R519
J 0
(-10050 7675);
DISPLAY 0.978723 (-10050 7675);
FORCEPROP 2 LAST CDS_LIB pure_quanta
J 0
(-9775 7675);
PAINT MONO (-9775 7675);
DISPLAY INVISIBLE (-9775 7675);
FORCEPROP 1 LAST PATH I7
J 0
(-9825 7825);
DISPLAY 0.978723 (-9825 7825);
PAINT WHITE (-9825 7825);
DISPLAY INVISIBLE (-9825 7825);
FORCEPROP 2 LAST CDS_LOCATION R519
J 0
(-9825 7875);
DISPLAY 1.021277 (-9825 7875);
DISPLAY INVISIBLE (-9825 7875);
FORCEPROP 2 LAST $SEC 1
J 0
(-9825 7875);
DISPLAY 0.680851 (-9825 7875);
PAINT MONO (-9825 7875);
DISPLAY INVISIBLE (-9825 7875);
FORCEPROP 2 LAST CDS_SEC 1
J 0
(-9825 7875);
DISPLAY 1.021277 (-9825 7875);
DISPLAY INVISIBLE (-9825 7875);
FORCEPROP 1 LASTPIN (-9875 7675) $PN 1
J 0
(-9863 7687);
DISPLAY 0.787234 (-9863 7687);
DISPLAY INVISIBLE (-9863 7687);
FORCEPROP 1 LASTPIN (-9675 7675) $PN 2
J 0
(-9713 7687);
DISPLAY 0.787234 (-9713 7687);
DISPLAY INVISIBLE (-9713 7687);
FORCEADD UNIVERSAL_GND..1
(-8850 7075);
FORCEPROP 3 LASTPIN (-8850 7125) SIG_NAME GND\g
J 0
(-8840 7135);
DISPLAY 0.659574 (-8840 7135);
PAINT MONO (-8840 7135);
DISPLAY INVISIBLE (-8840 7135);
FORCEPROP 2 LAST CDS_LIB logical_power
J 0
(-8850 7075);
DISPLAY INVISIBLE (-8850 7075);
FORCEPROP 1 LAST PATH I70
J 0
(-8775 7075);
DISPLAY 0.872340 (-8775 7075);
PAINT AQUA (-8775 7075);
DISPLAY INVISIBLE (-8775 7075);
FORCEPROP 1 LAST HDL_POWER GND
J 1
(-8825 7000);
DISPLAY 0.872340 (-8825 7000);
PAINT GREEN (-8825 7000);
DISPLAY INVISIBLE (-8825 7000);
FORCEADD UNIVERSAL_GND..1
(-8850 5850);
FORCEPROP 3 LASTPIN (-8850 5900) SIG_NAME GND\g
J 0
(-8840 5910);
DISPLAY 0.659574 (-8840 5910);
PAINT MONO (-8840 5910);
DISPLAY INVISIBLE (-8840 5910);
FORCEPROP 2 LAST CDS_LIB logical_power
J 0
(-8850 5850);
DISPLAY INVISIBLE (-8850 5850);
FORCEPROP 1 LAST PATH I71
J 0
(-8775 5850);
DISPLAY 0.872340 (-8775 5850);
PAINT AQUA (-8775 5850);
DISPLAY INVISIBLE (-8775 5850);
FORCEPROP 1 LAST HDL_POWER GND
J 1
(-8825 5775);
DISPLAY 0.872340 (-8825 5775);
PAINT GREEN (-8825 5775);
DISPLAY INVISIBLE (-8825 5775);
FORCEADD UNIVERSAL_GND..1
(-10900 5850);
FORCEPROP 3 LASTPIN (-10900 5900) SIG_NAME GND\g
J 0
(-10890 5910);
DISPLAY 0.659574 (-10890 5910);
PAINT MONO (-10890 5910);
DISPLAY INVISIBLE (-10890 5910);
FORCEPROP 2 LAST CDS_LIB logical_power
J 0
(-10900 5850);
DISPLAY INVISIBLE (-10900 5850);
FORCEPROP 1 LAST PATH I72
J 0
(-10825 5850);
DISPLAY 0.872340 (-10825 5850);
PAINT AQUA (-10825 5850);
DISPLAY INVISIBLE (-10825 5850);
FORCEPROP 1 LAST HDL_POWER GND
J 1
(-10875 5775);
DISPLAY 0.872340 (-10875 5775);
PAINT GREEN (-10875 5775);
DISPLAY INVISIBLE (-10875 5775);
FORCEADD UNIVERSAL_GND..1
(-10400 4525);
FORCEPROP 3 LASTPIN (-10400 4575) SIG_NAME GND\g
J 0
(-10390 4585);
DISPLAY 0.659574 (-10390 4585);
PAINT MONO (-10390 4585);
DISPLAY INVISIBLE (-10390 4585);
FORCEPROP 2 LAST CDS_LIB logical_power
J 0
(-10400 4525);
DISPLAY INVISIBLE (-10400 4525);
FORCEPROP 1 LAST PATH I73
J 0
(-10325 4525);
DISPLAY 0.872340 (-10325 4525);
PAINT AQUA (-10325 4525);
DISPLAY INVISIBLE (-10325 4525);
FORCEPROP 1 LAST HDL_POWER GND
J 1
(-10375 4450);
DISPLAY 0.872340 (-10375 4450);
PAINT GREEN (-10375 4450);
DISPLAY INVISIBLE (-10375 4450);
FORCEADD UNIVERSAL_GND..1
(-8850 4550);
FORCEPROP 3 LASTPIN (-8850 4600) SIG_NAME GND\g
J 0
(-8840 4610);
DISPLAY 0.659574 (-8840 4610);
PAINT MONO (-8840 4610);
DISPLAY INVISIBLE (-8840 4610);
FORCEPROP 2 LAST CDS_LIB logical_power
J 0
(-8850 4550);
DISPLAY INVISIBLE (-8850 4550);
FORCEPROP 1 LAST PATH I74
J 0
(-8775 4550);
DISPLAY 0.872340 (-8775 4550);
PAINT AQUA (-8775 4550);
DISPLAY INVISIBLE (-8775 4550);
FORCEPROP 1 LAST HDL_POWER GND
J 1
(-8825 4475);
DISPLAY 0.872340 (-8825 4475);
PAINT GREEN (-8825 4475);
DISPLAY INVISIBLE (-8825 4475);
FORCEADD Q_CAP..1
(-11150 7450);
FORCEPROP 1 LAST PART_NUMBER CH3474K1B04
J 0
(-11100 7300);
DISPLAY 0.319149 (-11100 7300);
DISPLAY INVISIBLE (-11100 7300);
FORCEPROP 1 LAST MATERIAL X7R
J 0
(-11100 7350);
DISPLAY 0.510638 (-11100 7350);
FORCEPROP 1 LAST PACK_TYPE C0402
J 0
(-11100 7250);
DISPLAY 0.510638 (-11100 7250);
FORCEPROP 1 LAST TOLERANCE 10%
J 0
(-11100 7400);
DISPLAY 0.510638 (-11100 7400);
FORCEPROP 1 LAST VALUE 0.047UF
J 0
(-11100 7500);
DISPLAY 0.510638 (-11100 7500);
FORCEPROP 1 LAST VOLTAGE 25V
J 0
(-11100 7450);
DISPLAY 0.510638 (-11100 7450);
FORCEPROP 1 LAST LOCATION C110
J 0
(-11100 7550);
DISPLAY 0.978723 (-11100 7550);
FORCEPROP 1 LASTPIN (-11150 7550) $PN 1
J 0
(-11140 7530);
DISPLAY 0.787234 (-11140 7530);
PAINT MONO (-11140 7530);
FORCEPROP 1 LASTPIN (-11150 7350) $PN 2
J 0
(-11140 7330);
DISPLAY 0.787234 (-11140 7330);
PAINT MONO (-11140 7330);
FORCEPROP 1 LAST PATH I76
J 0
(-11100 7600);
DISPLAY 0.978723 (-11100 7600);
PAINT WHITE (-11100 7600);
DISPLAY INVISIBLE (-11100 7600);
FORCEPROP 2 LAST CDS_LIB pure_quanta
J 0
(-11150 7450);
DISPLAY INVISIBLE (-11150 7450);
FORCEPROP 0 LAST $SEC 1
J 0
(-11100 7600);
DISPLAY 0.680851 (-11100 7600);
PAINT MONO (-11100 7600);
DISPLAY INVISIBLE (-11100 7600);
FORCEPROP 0 LAST CDS_SEC 1
J 0
(-11100 7600);
DISPLAY 1.021277 (-11100 7600);
DISPLAY INVISIBLE (-11100 7600);
FORCEADD Q_CAP..1
(-10900 7450);
FORCEPROP 1 LAST PART_NUMBER CH3474K1B04
J 0
(-10850 7300);
DISPLAY 0.319149 (-10850 7300);
DISPLAY INVISIBLE (-10850 7300);
FORCEPROP 1 LAST VALUE 0.047UF
J 0
(-10850 7500);
DISPLAY 0.404255 (-10850 7500);
FORCEPROP 1 LAST PACK_TYPE C0402
J 0
(-10850 7250);
DISPLAY 0.404255 (-10850 7250);
FORCEPROP 1 LAST VOLTAGE 25V
J 0
(-10850 7450);
DISPLAY 0.404255 (-10850 7450);
FORCEPROP 1 LAST TOLERANCE 10%
J 0
(-10850 7400);
DISPLAY 0.404255 (-10850 7400);
FORCEPROP 1 LAST MATERIAL X7R
J 0
(-10850 7350);
DISPLAY 0.404255 (-10850 7350);
FORCEPROP 1 LAST LOCATION C171
J 0
(-10850 7550);
DISPLAY 0.787234 (-10850 7550);
FORCEPROP 1 LASTPIN (-10900 7550) $PN 1
J 0
(-10890 7530);
DISPLAY 0.787234 (-10890 7530);
PAINT MONO (-10890 7530);
FORCEPROP 1 LASTPIN (-10900 7350) $PN 2
J 0
(-10890 7330);
DISPLAY 0.787234 (-10890 7330);
PAINT MONO (-10890 7330);
FORCEPROP 2 LAST CDS_LIB pure_quanta
J 0
(-10900 7450);
DISPLAY INVISIBLE (-10900 7450);
FORCEPROP 1 LAST PATH I77
J 0
(-10850 7600);
DISPLAY 0.978723 (-10850 7600);
PAINT WHITE (-10850 7600);
DISPLAY INVISIBLE (-10850 7600);
FORCEPROP 0 LAST $SEC 1
J 0
(-10850 7600);
DISPLAY 0.680851 (-10850 7600);
PAINT MONO (-10850 7600);
DISPLAY INVISIBLE (-10850 7600);
FORCEPROP 0 LAST CDS_SEC 1
J 0
(-10850 7600);
DISPLAY 1.021277 (-10850 7600);
DISPLAY INVISIBLE (-10850 7600);
FORCEADD Q_CAP..1
(-8850 7450);
FORCEPROP 1 LAST PART_NUMBER CH3474K1B04
J 0
(-8800 7300);
DISPLAY 0.319149 (-8800 7300);
DISPLAY INVISIBLE (-8800 7300);
FORCEPROP 1 LAST MATERIAL X7R
J 0
(-8800 7350);
DISPLAY 0.404255 (-8800 7350);
FORCEPROP 1 LAST PACK_TYPE C0402
J 0
(-8800 7250);
DISPLAY 0.404255 (-8800 7250);
FORCEPROP 1 LAST TOLERANCE 10%
J 0
(-8800 7400);
DISPLAY 0.404255 (-8800 7400);
FORCEPROP 1 LAST VOLTAGE 25V
J 0
(-8800 7450);
DISPLAY 0.404255 (-8800 7450);
FORCEPROP 1 LAST VALUE 0.047UF
J 0
(-8800 7500);
DISPLAY 0.404255 (-8800 7500);
FORCEPROP 1 LAST LOCATION C173
J 0
(-8800 7550);
DISPLAY 0.978723 (-8800 7550);
FORCEPROP 1 LASTPIN (-8850 7550) $PN 1
J 0
(-8840 7530);
DISPLAY 0.787234 (-8840 7530);
PAINT MONO (-8840 7530);
FORCEPROP 1 LASTPIN (-8850 7350) $PN 2
J 0
(-8840 7330);
DISPLAY 0.787234 (-8840 7330);
PAINT MONO (-8840 7330);
FORCEPROP 1 LAST PATH I78
J 0
(-8800 7600);
DISPLAY 0.978723 (-8800 7600);
PAINT WHITE (-8800 7600);
DISPLAY INVISIBLE (-8800 7600);
FORCEPROP 2 LAST CDS_LIB pure_quanta
J 0
(-8850 7450);
DISPLAY INVISIBLE (-8850 7450);
FORCEPROP 0 LAST $SEC 1
J 0
(-8800 7600);
DISPLAY 0.680851 (-8800 7600);
PAINT MONO (-8800 7600);
DISPLAY INVISIBLE (-8800 7600);
FORCEPROP 0 LAST CDS_SEC 1
J 0
(-8800 7600);
DISPLAY 1.021277 (-8800 7600);
DISPLAY INVISIBLE (-8800 7600);
FORCEADD Q_CAP..1
(-8850 6225);
FORCEPROP 1 LAST PART_NUMBER CH3474K1B04
J 0
(-8800 6075);
DISPLAY 0.319149 (-8800 6075);
DISPLAY INVISIBLE (-8800 6075);
FORCEPROP 1 LAST MATERIAL X7R
J 0
(-8800 6125);
DISPLAY 0.404255 (-8800 6125);
FORCEPROP 1 LAST TOLERANCE 10%
J 0
(-8800 6175);
DISPLAY 0.404255 (-8800 6175);
FORCEPROP 1 LAST VOLTAGE 25V
J 0
(-8800 6225);
DISPLAY 0.404255 (-8800 6225);
FORCEPROP 1 LAST PACK_TYPE C0402
J 0
(-8800 6025);
DISPLAY 0.404255 (-8800 6025);
FORCEPROP 1 LAST VALUE 0.047UF
J 0
(-8800 6275);
DISPLAY 0.404255 (-8800 6275);
FORCEPROP 1 LAST LOCATION C114
J 0
(-8800 6325);
DISPLAY 0.978723 (-8800 6325);
FORCEPROP 1 LASTPIN (-8850 6325) $PN 1
J 0
(-8840 6305);
DISPLAY 0.787234 (-8840 6305);
PAINT MONO (-8840 6305);
FORCEPROP 1 LASTPIN (-8850 6125) $PN 2
J 0
(-8840 6105);
DISPLAY 0.787234 (-8840 6105);
PAINT MONO (-8840 6105);
FORCEPROP 2 LAST CDS_LIB pure_quanta
J 0
(-8850 6225);
DISPLAY INVISIBLE (-8850 6225);
FORCEPROP 1 LAST PATH I79
J 0
(-8800 6375);
DISPLAY 0.978723 (-8800 6375);
PAINT WHITE (-8800 6375);
DISPLAY INVISIBLE (-8800 6375);
FORCEPROP 0 LAST $SEC 1
J 0
(-8800 6375);
DISPLAY 0.680851 (-8800 6375);
PAINT MONO (-8800 6375);
DISPLAY INVISIBLE (-8800 6375);
FORCEPROP 0 LAST CDS_SEC 1
J 0
(-8800 6375);
DISPLAY 1.021277 (-8800 6375);
DISPLAY INVISIBLE (-8800 6375);
FORCEADD UNIVERSAL_POWER..1
(-10200 7825);
FORCEPROP 3 LASTPIN (-10200 7775) SIG_NAME P3V3_AUX_CLK_GEN_VDD_CK440\g
J 0
(-10190 7785);
DISPLAY 0.659574 (-10190 7785);
PAINT MONO (-10190 7785);
DISPLAY INVISIBLE (-10190 7785);
FORCEPROP 1 LAST HDL_POWER P3V3_AUX_CLK_GEN_VDD_CK440
J 1
(-10200 7875);
DISPLAY 0.872340 (-10200 7875);
PAINT GREEN (-10200 7875);
FORCEPROP 2 LAST CDS_LIB logical_power
J 0
(-10200 7825);
PAINT MONO (-10200 7825);
DISPLAY INVISIBLE (-10200 7825);
FORCEPROP 1 LAST PATH I8
J 0
(-10150 7850);
DISPLAY 0.872340 (-10150 7850);
PAINT AQUA (-10150 7850);
DISPLAY INVISIBLE (-10150 7850);
FORCEADD Q_CAP..1
(-10900 6225);
FORCEPROP 1 LAST PART_NUMBER CH3474K1B04
J 0
(-10850 6075);
DISPLAY 0.319149 (-10850 6075);
DISPLAY INVISIBLE (-10850 6075);
FORCEPROP 1 LAST MATERIAL X7R
J 0
(-10850 6125);
DISPLAY 0.404255 (-10850 6125);
FORCEPROP 1 LAST TOLERANCE 10%
J 0
(-10850 6175);
DISPLAY 0.404255 (-10850 6175);
FORCEPROP 1 LAST PACK_TYPE C0402
J 0
(-10850 6025);
DISPLAY 0.404255 (-10850 6025);
FORCEPROP 1 LAST VALUE 0.047UF
J 0
(-10850 6275);
DISPLAY 0.404255 (-10850 6275);
FORCEPROP 1 LAST VOLTAGE 25V
J 0
(-10850 6225);
DISPLAY 0.404255 (-10850 6225);
FORCEPROP 1 LAST LOCATION C112
J 0
(-10850 6325);
DISPLAY 0.978723 (-10850 6325);
FORCEPROP 1 LASTPIN (-10900 6325) $PN 1
J 0
(-10890 6305);
DISPLAY 0.787234 (-10890 6305);
PAINT MONO (-10890 6305);
FORCEPROP 1 LASTPIN (-10900 6125) $PN 2
J 0
(-10890 6105);
DISPLAY 0.787234 (-10890 6105);
PAINT MONO (-10890 6105);
FORCEPROP 1 LAST PATH I80
J 0
(-10850 6375);
DISPLAY 0.978723 (-10850 6375);
PAINT WHITE (-10850 6375);
DISPLAY INVISIBLE (-10850 6375);
FORCEPROP 2 LAST CDS_LIB pure_quanta
J 0
(-10900 6225);
DISPLAY INVISIBLE (-10900 6225);
FORCEPROP 0 LAST $SEC 1
J 0
(-10850 6375);
DISPLAY 0.680851 (-10850 6375);
PAINT MONO (-10850 6375);
DISPLAY INVISIBLE (-10850 6375);
FORCEPROP 0 LAST CDS_SEC 1
J 0
(-10850 6375);
DISPLAY 1.021277 (-10850 6375);
DISPLAY INVISIBLE (-10850 6375);
FORCEADD Q_CAP..1
(-11150 6225);
FORCEPROP 1 LAST PART_NUMBER CH3474K1B04
J 0
(-11100 6075);
DISPLAY 0.319149 (-11100 6075);
DISPLAY INVISIBLE (-11100 6075);
FORCEPROP 1 LAST PACK_TYPE C0402
J 0
(-11100 6025);
DISPLAY 0.404255 (-11100 6025);
FORCEPROP 1 LAST VALUE 0.047UF
J 0
(-11100 6275);
DISPLAY 0.404255 (-11100 6275);
FORCEPROP 1 LAST TOLERANCE 10%
J 0
(-11100 6175);
DISPLAY 0.404255 (-11100 6175);
FORCEPROP 1 LAST VOLTAGE 25V
J 0
(-11100 6225);
DISPLAY 0.404255 (-11100 6225);
FORCEPROP 1 LAST MATERIAL X7R
J 0
(-11100 6125);
DISPLAY 0.404255 (-11100 6125);
FORCEPROP 1 LAST LOCATION C111
J 0
(-11100 6325);
DISPLAY 0.978723 (-11100 6325);
FORCEPROP 1 LASTPIN (-11150 6325) $PN 1
J 0
(-11140 6305);
DISPLAY 0.787234 (-11140 6305);
PAINT MONO (-11140 6305);
FORCEPROP 1 LASTPIN (-11150 6125) $PN 2
J 0
(-11140 6105);
DISPLAY 0.787234 (-11140 6105);
PAINT MONO (-11140 6105);
FORCEPROP 1 LAST PATH I81
J 0
(-11100 6375);
DISPLAY 0.978723 (-11100 6375);
PAINT WHITE (-11100 6375);
DISPLAY INVISIBLE (-11100 6375);
FORCEPROP 2 LAST CDS_LIB pure_quanta
J 0
(-11150 6225);
DISPLAY INVISIBLE (-11150 6225);
FORCEPROP 0 LAST $SEC 1
J 0
(-11100 6375);
DISPLAY 0.680851 (-11100 6375);
PAINT MONO (-11100 6375);
DISPLAY INVISIBLE (-11100 6375);
FORCEPROP 0 LAST CDS_SEC 1
J 0
(-11100 6375);
DISPLAY 1.021277 (-11100 6375);
DISPLAY INVISIBLE (-11100 6375);
FORCEADD Q_CAP..1
(-11500 7450);
FORCEPROP 1 LAST PART_NUMBER CH5104KEB02
J 0
(-11450 7250);
DISPLAY 0.510638 (-11450 7250);
DISPLAY INVISIBLE (-11450 7250);
FORCEPROP 1 LAST VALUE 1UF
J 0
(-11450 7500);
DISPLAY 0.638298 (-11450 7500);
FORCEPROP 1 LAST MATERIAL X6S
J 0
(-11450 7350);
DISPLAY 0.638298 (-11450 7350);
FORCEPROP 1 LAST PACK_TYPE C0402
J 0
(-11450 7300);
DISPLAY 0.638298 (-11450 7300);
FORCEPROP 1 LAST TOLERANCE 10%
J 0
(-11450 7400);
DISPLAY 0.638298 (-11450 7400);
FORCEPROP 1 LAST VOLTAGE 25V
J 0
(-11450 7450);
DISPLAY 0.638298 (-11450 7450);
FORCEPROP 1 LAST LOCATION C107
J 0
(-11450 7550);
DISPLAY 0.978723 (-11450 7550);
FORCEPROP 1 LASTPIN (-11500 7550) $PN 1
J 0
(-11490 7530);
DISPLAY 0.787234 (-11490 7530);
PAINT MONO (-11490 7530);
FORCEPROP 1 LASTPIN (-11500 7350) $PN 2
J 0
(-11490 7330);
DISPLAY 0.787234 (-11490 7330);
PAINT MONO (-11490 7330);
FORCEPROP 2 LAST BOM_COST VR_SYSTEM 
J 0
(-11450 7600);
DISPLAY 0.680851 (-11450 7600);
DISPLAY INVISIBLE (-11450 7600);
FORCEPROP 1 LAST PATH I82
J 0
(-11450 7600);
DISPLAY 0.978723 (-11450 7600);
PAINT WHITE (-11450 7600);
DISPLAY INVISIBLE (-11450 7600);
FORCEPROP 2 LAST CDS_LIB pure_quanta
J 0
(-11500 7450);
DISPLAY INVISIBLE (-11500 7450);
FORCEPROP 0 LAST $SEC 1
J 0
(-11450 7600);
DISPLAY 0.680851 (-11450 7600);
PAINT MONO (-11450 7600);
DISPLAY INVISIBLE (-11450 7600);
FORCEPROP 0 LAST CDS_SEC 1
J 0
(-11450 7600);
DISPLAY 1.021277 (-11450 7600);
DISPLAY INVISIBLE (-11450 7600);
FORCEADD Q_CAP..1
(-8850 4925);
FORCEPROP 1 LAST PART_NUMBER CH3474K1B04
J 0
(-8800 4775);
DISPLAY 0.319149 (-8800 4775);
DISPLAY INVISIBLE (-8800 4775);
FORCEPROP 1 LAST MATERIAL X7R
J 0
(-8800 4825);
DISPLAY 0.404255 (-8800 4825);
FORCEPROP 1 LAST TOLERANCE 10%
J 0
(-8800 4875);
DISPLAY 0.404255 (-8800 4875);
FORCEPROP 1 LAST VOLTAGE 25V
J 0
(-8800 4925);
DISPLAY 0.404255 (-8800 4925);
FORCEPROP 1 LAST PACK_TYPE C0402
J 0
(-8800 4725);
DISPLAY 0.404255 (-8800 4725);
FORCEPROP 1 LAST VALUE 0.047UF
J 0
(-8800 4975);
DISPLAY 0.404255 (-8800 4975);
FORCEPROP 1 LAST LOCATION C120
J 0
(-8800 5025);
DISPLAY 0.978723 (-8800 5025);
FORCEPROP 1 LASTPIN (-8850 5025) $PN 1
J 0
(-8840 5005);
DISPLAY 0.787234 (-8840 5005);
PAINT MONO (-8840 5005);
FORCEPROP 1 LASTPIN (-8850 4825) $PN 2
J 0
(-8840 4805);
DISPLAY 0.787234 (-8840 4805);
PAINT MONO (-8840 4805);
FORCEPROP 1 LAST PATH I85
J 0
(-8800 5075);
DISPLAY 0.978723 (-8800 5075);
PAINT WHITE (-8800 5075);
DISPLAY INVISIBLE (-8800 5075);
FORCEPROP 2 LAST CDS_LIB pure_quanta
J 0
(-8850 4925);
DISPLAY INVISIBLE (-8850 4925);
FORCEPROP 0 LAST $SEC 1
J 0
(-8800 5075);
DISPLAY 0.680851 (-8800 5075);
PAINT MONO (-8800 5075);
DISPLAY INVISIBLE (-8800 5075);
FORCEPROP 0 LAST CDS_SEC 1
J 0
(-8800 5075);
DISPLAY 1.021277 (-8800 5075);
DISPLAY INVISIBLE (-8800 5075);
FORCEADD Q_CAP..1
(-10400 4925);
FORCEPROP 1 LAST PART_NUMBER CH3474K1B04
J 0
(-10350 4775);
DISPLAY 0.319149 (-10350 4775);
DISPLAY INVISIBLE (-10350 4775);
FORCEPROP 1 LAST VALUE 0.047UF
J 0
(-10350 4975);
DISPLAY 0.404255 (-10350 4975);
FORCEPROP 1 LAST PACK_TYPE C0402
J 0
(-10350 4725);
DISPLAY 0.404255 (-10350 4725);
FORCEPROP 1 LAST VOLTAGE 25V
J 0
(-10350 4925);
DISPLAY 0.404255 (-10350 4925);
FORCEPROP 1 LAST TOLERANCE 10%
J 0
(-10350 4875);
DISPLAY 0.404255 (-10350 4875);
FORCEPROP 1 LAST MATERIAL X7R
J 0
(-10350 4825);
DISPLAY 0.404255 (-10350 4825);
FORCEPROP 1 LAST LOCATION C119
J 0
(-10350 5025);
DISPLAY 0.978723 (-10350 5025);
FORCEPROP 1 LASTPIN (-10400 5025) $PN 1
J 0
(-10390 5005);
DISPLAY 0.787234 (-10390 5005);
PAINT MONO (-10390 5005);
FORCEPROP 1 LASTPIN (-10400 4825) $PN 2
J 0
(-10390 4805);
DISPLAY 0.787234 (-10390 4805);
PAINT MONO (-10390 4805);
FORCEPROP 1 LAST PATH I86
J 0
(-10350 5075);
DISPLAY 0.978723 (-10350 5075);
PAINT WHITE (-10350 5075);
DISPLAY INVISIBLE (-10350 5075);
FORCEPROP 2 LAST CDS_LIB pure_quanta
J 0
(-10400 4925);
DISPLAY INVISIBLE (-10400 4925);
FORCEPROP 0 LAST $SEC 1
J 0
(-10350 5075);
DISPLAY 0.680851 (-10350 5075);
PAINT MONO (-10350 5075);
DISPLAY INVISIBLE (-10350 5075);
FORCEPROP 0 LAST CDS_SEC 1
J 0
(-10350 5075);
DISPLAY 1.021277 (-10350 5075);
DISPLAY INVISIBLE (-10350 5075);
FORCEADD Q_CAP..1
(-10650 4925);
FORCEPROP 1 LAST PART_NUMBER CH3474K1B04
J 0
(-10600 4775);
DISPLAY 0.319149 (-10600 4775);
DISPLAY INVISIBLE (-10600 4775);
FORCEPROP 1 LAST VALUE 0.047UF
J 0
(-10600 4975);
DISPLAY 0.404255 (-10600 4975);
FORCEPROP 1 LAST PACK_TYPE C0402
J 0
(-10600 4725);
DISPLAY 0.404255 (-10600 4725);
FORCEPROP 1 LAST VOLTAGE 25V
J 0
(-10600 4925);
DISPLAY 0.404255 (-10600 4925);
FORCEPROP 1 LAST TOLERANCE 10%
J 0
(-10600 4875);
DISPLAY 0.404255 (-10600 4875);
FORCEPROP 1 LAST MATERIAL X7R
J 0
(-10600 4825);
DISPLAY 0.404255 (-10600 4825);
FORCEPROP 1 LAST LOCATION C117
J 0
(-10600 5025);
DISPLAY 0.978723 (-10600 5025);
FORCEPROP 1 LASTPIN (-10650 5025) $PN 1
J 0
(-10640 5005);
DISPLAY 0.787234 (-10640 5005);
PAINT MONO (-10640 5005);
FORCEPROP 1 LASTPIN (-10650 4825) $PN 2
J 0
(-10640 4805);
DISPLAY 0.787234 (-10640 4805);
PAINT MONO (-10640 4805);
FORCEPROP 1 LAST PATH I87
J 0
(-10600 5075);
DISPLAY 0.978723 (-10600 5075);
PAINT WHITE (-10600 5075);
DISPLAY INVISIBLE (-10600 5075);
FORCEPROP 2 LAST CDS_LIB pure_quanta
J 0
(-10650 4925);
DISPLAY INVISIBLE (-10650 4925);
FORCEPROP 0 LAST $SEC 1
J 0
(-10600 5075);
DISPLAY 0.680851 (-10600 5075);
PAINT MONO (-10600 5075);
DISPLAY INVISIBLE (-10600 5075);
FORCEPROP 0 LAST CDS_SEC 1
J 0
(-10600 5075);
DISPLAY 1.021277 (-10600 5075);
DISPLAY INVISIBLE (-10600 5075);
FORCEADD Q_CAP..1
(-10900 4925);
FORCEPROP 1 LAST PART_NUMBER CH3474K1B04
J 0
(-10850 4775);
DISPLAY 0.319149 (-10850 4775);
DISPLAY INVISIBLE (-10850 4775);
FORCEPROP 1 LAST PACK_TYPE C0402
J 0
(-10850 4725);
DISPLAY 0.404255 (-10850 4725);
FORCEPROP 1 LAST MATERIAL X7R
J 0
(-10850 4825);
DISPLAY 0.404255 (-10850 4825);
FORCEPROP 1 LAST TOLERANCE 10%
J 0
(-10850 4875);
DISPLAY 0.404255 (-10850 4875);
FORCEPROP 1 LAST VALUE 0.047UF
J 0
(-10850 4975);
DISPLAY 0.404255 (-10850 4975);
FORCEPROP 1 LAST VOLTAGE 25V
J 0
(-10850 4925);
DISPLAY 0.404255 (-10850 4925);
FORCEPROP 1 LAST LOCATION C116
J 0
(-10850 5025);
DISPLAY 0.978723 (-10850 5025);
FORCEPROP 1 LASTPIN (-10900 5025) $PN 1
J 0
(-10890 5005);
DISPLAY 0.787234 (-10890 5005);
PAINT MONO (-10890 5005);
FORCEPROP 1 LASTPIN (-10900 4825) $PN 2
J 0
(-10890 4805);
DISPLAY 0.787234 (-10890 4805);
PAINT MONO (-10890 4805);
FORCEPROP 1 LAST PATH I88
J 0
(-10850 5075);
DISPLAY 0.978723 (-10850 5075);
PAINT WHITE (-10850 5075);
DISPLAY INVISIBLE (-10850 5075);
FORCEPROP 2 LAST CDS_LIB pure_quanta
J 0
(-10900 4925);
DISPLAY INVISIBLE (-10900 4925);
FORCEPROP 0 LAST $SEC 1
J 0
(-10850 5075);
DISPLAY 0.680851 (-10850 5075);
PAINT MONO (-10850 5075);
DISPLAY INVISIBLE (-10850 5075);
FORCEPROP 0 LAST CDS_SEC 1
J 0
(-10850 5075);
DISPLAY 1.021277 (-10850 5075);
DISPLAY INVISIBLE (-10850 5075);
FORCEADD Q_CAP..1
(-11150 4925);
FORCEPROP 1 LAST PART_NUMBER CH3474K1B04
J 0
(-11100 4775);
DISPLAY 0.319149 (-11100 4775);
DISPLAY INVISIBLE (-11100 4775);
FORCEPROP 1 LAST VALUE 0.047UF
J 0
(-11100 4975);
DISPLAY 0.404255 (-11100 4975);
FORCEPROP 1 LAST VOLTAGE 25V
J 0
(-11100 4925);
DISPLAY 0.404255 (-11100 4925);
FORCEPROP 1 LAST TOLERANCE 10%
J 0
(-11100 4875);
DISPLAY 0.404255 (-11100 4875);
FORCEPROP 1 LAST MATERIAL X7R
J 0
(-11100 4825);
DISPLAY 0.404255 (-11100 4825);
FORCEPROP 1 LAST PACK_TYPE C0402
J 0
(-11100 4725);
DISPLAY 0.404255 (-11100 4725);
FORCEPROP 1 LAST LOCATION C115
J 0
(-11100 5025);
DISPLAY 0.978723 (-11100 5025);
FORCEPROP 1 LASTPIN (-11150 5025) $PN 1
J 0
(-11140 5005);
DISPLAY 0.787234 (-11140 5005);
PAINT MONO (-11140 5005);
FORCEPROP 1 LASTPIN (-11150 4825) $PN 2
J 0
(-11140 4805);
DISPLAY 0.787234 (-11140 4805);
PAINT MONO (-11140 4805);
FORCEPROP 1 LAST PATH I89
J 0
(-11100 5075);
DISPLAY 0.978723 (-11100 5075);
PAINT WHITE (-11100 5075);
DISPLAY INVISIBLE (-11100 5075);
FORCEPROP 2 LAST CDS_LIB pure_quanta
J 0
(-11150 4925);
DISPLAY INVISIBLE (-11150 4925);
FORCEPROP 0 LAST $SEC 1
J 0
(-11100 5075);
DISPLAY 0.680851 (-11100 5075);
PAINT MONO (-11100 5075);
DISPLAY INVISIBLE (-11100 5075);
FORCEPROP 0 LAST CDS_SEC 1
J 0
(-11100 5075);
DISPLAY 1.021277 (-11100 5075);
DISPLAY INVISIBLE (-11100 5075);
FORCEADD CAD_NOTE..1
(-7800 6425);
FORCEPROP 0 LAST S1 PLACE EACH 0.047UF CAP AT LESS THAN 150 MILS FROM RESPECTIVE PWR PIN
J 0
(-7950 6250);
DISPLAY 1.276596 (-7950 6250);
PAINT WHITE (-7950 6250);
FORCEPROP 2 LAST CDS_LIB logical_power
J 0
(-7800 6425);
PAINT MONO (-7800 6425);
DISPLAY INVISIBLE (-7800 6425);
FORCEPROP 1 LAST COMMENT_BODY TRUE
J 0
(-7775 6525);
DISPLAY 0.978723 (-7775 6525);
DISPLAY INVISIBLE (-7775 6525);
FORCEADD CAD_NOTE..1
(-7775 7525);
FORCEPROP 0 LAST S1 PAIR EACH 0.047UF CAP WITH A PWR PIN. FOR ALL FILTERS
J 0
(-7925 7350);
DISPLAY 1.276596 (-7925 7350);
PAINT WHITE (-7925 7350);
FORCEPROP 1 LAST COMMENT_BODY TRUE
J 0
(-7750 7625);
DISPLAY 0.978723 (-7750 7625);
DISPLAY INVISIBLE (-7750 7625);
FORCEPROP 2 LAST CDS_LIB logical_power
J 0
(-7775 7525);
PAINT MONO (-7775 7525);
DISPLAY INVISIBLE (-7775 7525);
FORCEADD QUANTA_TITLE_BLOCK_C..1
(-3625 2350);
FORCEPROP 0 LAST CDS_CON_LAST_MODIFIED Fri Aug 25 14:03:26 2023
J 0
(-5510 2365);
DISPLAY INVISIBLE (-5510 2365);
FORCEPROP 2 LAST CUSTOM_TXT_CDS <XR_PAGE_TITLE>
J 0
(-11515 7600);
DISPLAY 0.638298 (-11515 7600);
PAINT PINK (-11515 7600);
DISPLAY INVISIBLE (-11515 7600);
FORCEPROP 2 LAST CUSTOM_TXT_CDS <NAME_2>
J 0
(-6800 2400);
FORCEPROP 2 LAST CUSTOM_TXT_CDS <NAME_1>
J 0
(-6800 2525);
FORCEPROP 2 LAST CUSTOM_TXT_CDS <Q_NUMBER>
J 0
(-5028 2453);
DISPLAY 1.212766 (-5028 2453);
FORCEPROP 2 LAST CUSTOM_TXT_CDS <Q_PROJ>
J 0
(-6007 2452);
DISPLAY 1.212766 (-6007 2452);
FORCEPROP 2 LAST CUSTOM_TXT_CDS <Q_REV>
J 0
(-3809 2453);
DISPLAY 1.212766 (-3809 2453);
FORCEPROP 2 LAST CUSTOM_TXT_CDS <CON_PAGE_NUM> OF <CON_TOTAL_PAGES>
J 0
(-4071 2368);
DISPLAY 0.978723 (-4071 2368);
FORCEPROP 2 LAST CUSTOM_TXT_CDS <CON_LAST_MODIFIED>
J 0
(-5510 2365);
DISPLAY 0.978723 (-5510 2365);
FORCEPROP 1 LAST Q_TITLE CLK- CK440 POWER FILTER
J 0
(-12941 2376);
DISPLAY 2.446809 (-12941 2376);
PAINT GREEN (-12941 2376);
FORCEPROP 1 LAST Q_DEPT 
J 1
(-7388 2399);
DISPLAY 1.957447 (-7388 2399);
PAINT GREEN (-7388 2399);
FORCEPROP 2 LAST CDS_XR_PAGE_TITLE CR-210 : @S9S_MB_2U_LIB.S9S_MB_2U(SCH_1):PAGE210
J 0
(-11515 7600);
DISPLAY 0.638298 (-11515 7600);
PAINT PINK (-11515 7600);
DISPLAY INVISIBLE (-11515 7600);
FORCEPROP 2 LAST CDS_LIB pure_quanta
J 0
(-3625 2350);
DISPLAY INVISIBLE (-3625 2350);
FORCEPROP 1 LAST CDS_LMAN_SYM_OUTLINE -9475,6775,100,-125
J 0
(-3625 2350);
DISPLAY 0.468085 (-3625 2350);
PAINT GREEN (-3625 2350);
DISPLAY INVISIBLE (-3625 2350);
FORCEPROP 1 LAST COMMENT_BODY TRUE
J 0
(-3613 2337);
DISPLAY 0.978723 (-3613 2337);
PAINT GREEN (-3613 2337);
DISPLAY INVISIBLE (-3613 2337);
FORCEPROP 2 LAST PAGE_BORDER TRUE
J 0
(-11515 7600);
DISPLAY 0.638298 (-11515 7600);
PAINT PINK (-11515 7600);
DISPLAY INVISIBLE (-11515 7600);
WIRE 16 -1 (-10200 5150)(-10200 5250);
WIRE 16 -1 (-10200 5150)(-10400 5150);
WIRE 16 -1 (-9875 5150)(-10200 5150);
WIRE 16 -1 (-8850 6450)(-8850 6550);
WIRE 16 -1 (-9250 6450)(-8850 6450);
WIRE 16 -1 (-8850 6325)(-8850 6450);
WIRE 16 -1 (-12400 6450)(-12400 6700);
WIRE 16 -1 (-12175 6450)(-12400 6450);
WIRE 16 -1 (-10200 6450)(-10200 6550);
WIRE 16 -1 (-10900 6450)(-10200 6450);
WIRE 16 -1 (-9875 6450)(-10200 6450);
WIRE 16 -1 (-10200 7675)(-10200 7775);
WIRE 16 -1 (-10900 7675)(-10200 7675);
WIRE 16 -1 (-9875 7675)(-10200 7675);
WIRE 16 -1 (-12400 5150)(-12400 5400);
WIRE 16 -1 (-12175 5150)(-12400 5150);
WIRE 16 -1 (-8850 5150)(-8850 5250);
WIRE 16 -1 (-9250 5150)(-8850 5150);
WIRE 16 -1 (-8850 5025)(-8850 5150);
WIRE 16 -1 (-8850 7675)(-8850 7775);
WIRE 16 -1 (-9250 7675)(-8850 7675);
WIRE 16 -1 (-8850 7550)(-8850 7675);
WIRE 16 -1 (-12400 7675)(-12400 7925);
WIRE 16 -1 (-12175 7675)(-12400 7675);
WIRE 16 -1 (-8850 4600)(-8850 4700);
WIRE 16 -1 (-10400 4575)(-10400 4700);
WIRE 16 -1 (-10900 5900)(-10900 6000);
WIRE 16 -1 (-8850 5900)(-8850 6000);
WIRE 16 -1 (-8850 7125)(-8850 7225);
WIRE 16 -1 (-10900 7125)(-10900 7225);
WIRE 16 -1 (-11850 5025)(-11850 5150);
WIRE 16 -1 (-11975 5150)(-11850 5150);
WIRE 16 -1 (-11500 5025)(-11500 5150);
WIRE 16 -1 (-11850 5150)(-11500 5150);
WIRE 16 -1 (-11150 5150)(-11500 5150);
WIRE 16 -1 (-11150 5025)(-11150 5150);
WIRE 16 -1 (-10900 5025)(-10900 5150);
WIRE 16 -1 (-10900 5150)(-11150 5150);
WIRE 16 -1 (-10650 5025)(-10650 5150);
WIRE 16 -1 (-10650 5150)(-10900 5150);
WIRE 16 -1 (-10400 5025)(-10400 5150);
WIRE 16 -1 (-10400 5150)(-10650 5150);
WIRE 16 -1 (-9250 6125)(-9250 6000);
WIRE 16 -1 (-9250 6000)(-8850 6000);
WIRE 16 -1 (-8850 6125)(-8850 6000);
WIRE 16 -1 (-10900 7550)(-10900 7675);
WIRE 16 -1 (-11150 7550)(-11150 7675);
WIRE 16 -1 (-10900 7675)(-11150 7675);
WIRE 16 -1 (-11500 7550)(-11500 7675);
WIRE 16 -1 (-11150 7675)(-11500 7675);
WIRE 16 -1 (-11850 7550)(-11850 7675);
WIRE 16 -1 (-11850 7675)(-11500 7675);
WIRE 16 -1 (-11975 7675)(-11850 7675);
WIRE 16 -1 (-11850 4700)(-11850 4825);
WIRE 16 -1 (-11850 4700)(-11500 4700);
WIRE 16 -1 (-11500 4825)(-11500 4700);
WIRE 16 -1 (-11150 4700)(-11500 4700);
WIRE 16 -1 (-11150 4700)(-11150 4825);
WIRE 16 -1 (-10900 4700)(-11150 4700);
WIRE 16 -1 (-10900 4700)(-10900 4825);
WIRE 16 -1 (-10650 4700)(-10900 4700);
WIRE 16 -1 (-10650 4700)(-10650 4825);
WIRE 16 -1 (-10400 4700)(-10650 4700);
WIRE 16 -1 (-10400 4700)(-10400 4825);
WIRE 16 -1 (-10900 6325)(-10900 6450);
WIRE 16 -1 (-11150 6325)(-11150 6450);
WIRE 16 -1 (-10900 6450)(-11150 6450);
WIRE 16 -1 (-11500 6325)(-11500 6450);
WIRE 16 -1 (-11150 6450)(-11500 6450);
WIRE 16 -1 (-11975 6450)(-11850 6450);
WIRE 16 -1 (-11850 6450)(-11500 6450);
WIRE 16 -1 (-11850 6325)(-11850 6450);
WIRE 16 -1 (-11850 6000)(-11850 6125);
WIRE 16 -1 (-11850 6000)(-11500 6000);
WIRE 16 -1 (-11500 6125)(-11500 6000);
WIRE 16 -1 (-11150 6000)(-11500 6000);
WIRE 16 -1 (-11150 6000)(-11150 6125);
WIRE 16 -1 (-10900 6000)(-11150 6000);
WIRE 16 -1 (-10900 6000)(-10900 6125);
WIRE 16 -1 (-9675 5150)(-9250 5150);
WIRE 16 -1 (-9250 5025)(-9250 5150);
WIRE 16 -1 (-9250 4825)(-9250 4700);
WIRE 16 -1 (-9250 4700)(-8850 4700);
WIRE 16 -1 (-8850 4825)(-8850 4700);
WIRE 16 -1 (-11850 7225)(-11850 7350);
WIRE 16 -1 (-11850 7225)(-11500 7225);
WIRE 16 -1 (-11500 7350)(-11500 7225);
WIRE 16 -1 (-11150 7225)(-11500 7225);
WIRE 16 -1 (-11150 7225)(-11150 7350);
WIRE 16 -1 (-10900 7225)(-11150 7225);
WIRE 16 -1 (-10900 7225)(-10900 7350);
WIRE 16 -1 (-9675 6450)(-9250 6450);
WIRE 16 -1 (-9250 6325)(-9250 6450);
WIRE 16 -1 (-9250 7350)(-9250 7225);
WIRE 16 -1 (-9250 7225)(-8850 7225);
WIRE 16 -1 (-8850 7350)(-8850 7225);
WIRE 16 -1 (-9675 7675)(-9250 7675);
WIRE 16 -1 (-9250 7550)(-9250 7675);
DOT 1 (-10900 4700);
DOT 1 (-11500 7225);
DOT 1 (-11500 6450);
DOT 1 (-11150 7225);
DOT 1 (-10900 7225);
DOT 1 (-11150 6450);
DOT 1 (-10900 6000);
DOT 1 (-10650 5150);
DOT 1 (-8850 7675);
DOT 1 (-11500 4700);
DOT 1 (-10400 5150);
DOT 1 (-10200 7675);
DOT 1 (-10200 6450);
DOT 1 (-8850 5150);
DOT 1 (-8850 6450);
DOT 1 (-8850 7225);
DOT 1 (-9250 7675);
DOT 1 (-8850 6000);
DOT 1 (-8850 4700);
DOT 1 (-10200 5150);
DOT 1 (-10400 4700);
DOT 1 (-9250 5150);
DOT 1 (-10650 4700);
DOT 1 (-11850 5150);
DOT 1 (-11500 5150);
DOT 1 (-11150 4700);
DOT 1 (-11150 5150);
DOT 1 (-10900 5150);
DOT 1 (-10900 6450);
DOT 1 (-11850 7675);
DOT 1 (-10900 7675);
DOT 1 (-11150 7675);
DOT 1 (-11850 6450);
DOT 1 (-11500 7675);
DOT 1 (-9250 6450);
DOT 1 (-11500 6000);
DOT 1 (-11150 6000);
QUIT
